G04 ================== begin FILE IDENTIFICATION RECORD ==================*
G04 Layout Name:  15750-1.brd*
G04 Film Name:    L5GND*
G04 File Format:  Gerber RS274X*
G04 File Origin:  Cadence Allegro 16.5-S056*
G04 Origin Date:  Fri Dec 30 13:21:38 2016*
G04 *
G04 Layer:  VIA CLASS/L5GND*
G04 Layer:  PIN/L5GND*
G04 Layer:  ETCH/L5GND*
G04 Layer:  DRAWING FORMAT/LAYER_L5GND*
G04 Layer:  DRAWING FORMAT/LAYER_PCB_STORY*
G04 *
G04 Offset:    (0.00 0.00)*
G04 Mirror:    No*
G04 Mode:      Negative*
G04 Rotation:  0*
G04 FullContactRelief:  No*
G04 UndefLineWidth:     6.00*
G04 ================== end FILE IDENTIFICATION RECORD ====================*
%FSLAX35Y35*MOIN*%
%IR0*IPPOS*OFA0.00000B0.00000*MIA0B0*SFA1.00000B1.00000*%
%ADD15C,.03*%
%ADD14C,.032*%
%ADD17C,.072*%
%ADD16C,.091*%
%ADD20C,.093*%
%ADD18C,.068*%
%AMMACRO12*
4,1,15,.00398,.00044,
.003999,.000208,
.004004,-.000025,
.003996,-.000258,
.00398,-.00044,
.00483,-.00129,
.004897,-.001007,
.004947,-.000721,
.004981,-.000432,
.004997,-.000141,
.004997,.000149,
.00498,.00044,
.004946,.000729,
.004895,.001015,
.00483,.00129,
.00398,.00044,
0.0*
4,1,15,.00044,-.00398,
.000208,-.003999,
-.000025,-.004004,
-.000258,-.003996,
-.00044,-.00398,
-.00129,-.00483,
-.001007,-.004897,
-.000721,-.004947,
-.000432,-.004981,
-.000141,-.004997,
.000149,-.004997,
.00044,-.00498,
.000729,-.004946,
.001015,-.004895,
.00129,-.00483,
.00044,-.00398,
0.0*
4,1,15,-.00398,-.00044,
-.003999,-.000208,
-.004004,.000025,
-.003996,.000258,
-.00398,.00044,
-.00483,.00129,
-.004897,.001007,
-.004947,.000721,
-.004981,.000432,
-.004997,.000141,
-.004997,-.000149,
-.00498,-.00044,
-.004946,-.000729,
-.004895,-.001015,
-.00483,-.00129,
-.00398,-.00044,
0.0*
4,1,15,-.00044,.00398,
-.000208,.003999,
.000025,.004004,
.000258,.003996,
.00044,.00398,
.00129,.00483,
.001007,.004897,
.000721,.004947,
.000432,.004981,
.000141,.004997,
-.000149,.004997,
-.00044,.00498,
-.000729,.004946,
-.001015,.004895,
-.00129,.00483,
-.00044,.00398,
0.0*
%
%ADD12MACRO12*%
%AMMACRO19*
4,1,13,.02632,.01218,
.028035,.007425,
.028899,.002443,
.028884,-.002612,
.027991,-.007588,
.02632,-.01218,
.03005,-.01591,
.032356,-.01045,
.033679,-.004673,
.033979,.001247,
.033246,.007128,
.031504,.012793,
.03005,.01591,
.02632,.01218,
270.*
4,1,13,.01218,-.02632,
.007425,-.028035,
.002443,-.028899,
-.002612,-.028884,
-.007588,-.027991,
-.01218,-.02632,
-.01591,-.03005,
-.01045,-.032356,
-.004673,-.033679,
.001247,-.033979,
.007128,-.033246,
.012793,-.031504,
.01591,-.03005,
.01218,-.02632,
270.*
4,1,13,-.02632,-.01218,
-.028035,-.007425,
-.028899,-.002443,
-.028884,.002612,
-.027991,.007588,
-.02632,.01218,
-.03005,.01591,
-.032356,.01045,
-.033679,.004673,
-.033979,-.001247,
-.033246,-.007128,
-.031504,-.012793,
-.03005,-.01591,
-.02632,-.01218,
270.*
4,1,13,-.01218,.02632,
-.007425,.028035,
-.002443,.028899,
.002612,.028884,
.007588,.027991,
.01218,.02632,
.01591,.03005,
.01045,.032356,
.004673,.033679,
-.001247,.033979,
-.007128,.033246,
-.012793,.031504,
-.01591,.03005,
-.01218,.02632,
270.*
%
%ADD19MACRO19*%
%ADD10C,.114*%
%AMMACRO13*
4,1,15,.00398,.00044,
.003999,.000208,
.004004,-.000025,
.003996,-.000258,
.00398,-.00044,
.00483,-.00129,
.004897,-.001007,
.004947,-.000721,
.004981,-.000432,
.004997,-.000141,
.004997,.000149,
.00498,.00044,
.004946,.000729,
.004895,.001015,
.00483,.00129,
.00398,.00044,
270.*
4,1,15,.00044,-.00398,
.000208,-.003999,
-.000025,-.004004,
-.000258,-.003996,
-.00044,-.00398,
-.00129,-.00483,
-.001007,-.004897,
-.000721,-.004947,
-.000432,-.004981,
-.000141,-.004997,
.000149,-.004997,
.00044,-.00498,
.000729,-.004946,
.001015,-.004895,
.00129,-.00483,
.00044,-.00398,
270.*
4,1,15,-.00398,-.00044,
-.003999,-.000208,
-.004004,.000025,
-.003996,.000258,
-.00398,.00044,
-.00483,.00129,
-.004897,.001007,
-.004947,.000721,
-.004981,.000432,
-.004997,.000141,
-.004997,-.000149,
-.00498,-.00044,
-.004946,-.000729,
-.004895,-.001015,
-.00483,-.00129,
-.00398,-.00044,
270.*
4,1,15,-.00044,.00398,
-.000208,.003999,
.000025,.004004,
.000258,.003996,
.00044,.00398,
.00129,.00483,
.001007,.004897,
.000721,.004947,
.000432,.004981,
.000141,.004997,
-.000149,.004997,
-.00044,.00498,
-.000729,.004946,
-.001015,.004895,
-.00129,.00483,
-.00044,.00398,
270.*
%
%ADD13MACRO13*%
%AMMACRO11*
4,1,16,.07256,.04427,
.079145,.030998,
.083325,.016783,
.084974,.002059,
.08404,-.012728,
.080553,-.027128,
.074619,-.040704,
.07256,-.04427,
.07619,-.04791,
.083352,-.033952,
.087981,-.018962,
.089937,-.003396,
.089161,.012273,
.085675,.027569,
.079586,.042027,
.07619,.04791,
.07256,.04427,
0.0*
4,1,16,.04427,-.07256,
.030998,-.079145,
.016783,-.083325,
.002059,-.084974,
-.012728,-.08404,
-.027128,-.080553,
-.040704,-.074619,
-.04427,-.07256,
-.04791,-.07619,
-.033952,-.083352,
-.018962,-.087981,
-.003396,-.089937,
.012273,-.089161,
.027569,-.085675,
.042027,-.079586,
.04791,-.07619,
.04427,-.07256,
0.0*
4,1,16,-.07256,-.04427,
-.079145,-.030998,
-.083325,-.016783,
-.084974,-.002059,
-.08404,.012728,
-.080553,.027128,
-.074619,.040704,
-.07256,.04427,
-.07619,.04791,
-.083352,.033952,
-.087981,.018962,
-.089937,.003396,
-.089161,-.012273,
-.085675,-.027569,
-.079586,-.042027,
-.07619,-.04791,
-.07256,-.04427,
0.0*
4,1,16,-.04427,.07256,
-.030998,.079145,
-.016783,.083325,
-.002059,.084974,
.012728,.08404,
.027128,.080553,
.040704,.074619,
.04427,.07256,
.04791,.07619,
.033952,.083352,
.018962,.087981,
.003396,.089937,
-.012273,.089161,
-.027569,.085675,
-.042027,.079586,
-.04791,.07619,
-.04427,.07256,
0.0*
%
%ADD11MACRO11*%
%ADD21C,.02*%
%ADD22C,.006*%
%ADD25C,.06804*%
%ADD24C,.08704*%
%ADD26C,.08904*%
%ADD23O,.04824X.09264*%
G75*
%LPD*%
G75*
G36*
G01X-6000Y-6000D02*
X355409D01*
Y369425D01*
X-6000D01*
Y-6000D01*
G37*
%LPC*%
G75*
G36*
G01X223819Y1904D02*
G02X217849Y7874I0J5970D01*
G01Y258071D01*
G03X208071Y267849I-9778J0D01*
G01X7874D01*
G02X1904Y273819I0J5970D01*
G01Y355551D01*
G02X7874Y361521I5970J0D01*
G01X341535D01*
G02X347505Y355551I0J-5970D01*
G01Y278779D01*
G02X347441Y278715I-64J0D01*
G01X339566D01*
G03X335694Y274843I1J-3873D01*
G01Y219567D01*
G03X339567Y215694I3873J0D01*
G01X347441D01*
G02X347505Y215630I0J-64D01*
G01Y195925D01*
G02X347441Y195861I-64J0D01*
G01X321062D01*
G03X317190Y191989I1J-3873D01*
G01Y175256D01*
G03X321063Y171383I3873J0D01*
G01X323938D01*
G02X324212Y170691I0J-400D01*
G03X323732Y169587I1032J-1105D01*
G01Y166437D01*
G03X325720Y165002I1512J0D01*
G02X326246Y164623I126J-379D01*
G01Y161952D01*
G02X325720Y161573I-400J0D01*
G03X323732Y160138I-476J-1435D01*
G01Y156988D01*
G03X325720Y155553I1512J0D01*
G02X326246Y155174I126J-379D01*
G01Y152502D01*
G02X325720Y152122I-400J0D01*
G03X323734Y150689I-476J-1433D01*
G01Y147540D01*
G03X325720Y146107I1510J0D01*
G02X326246Y145727I126J-380D01*
G01Y111558D01*
G02X325720Y111179I-400J0D01*
G03X323732Y109744I-476J-1435D01*
G01Y106595D01*
G03X325720Y105160I1512J0D01*
G02X326246Y104781I126J-379D01*
G01Y102110D01*
G02X325720Y101731I-400J0D01*
G03X323732Y100296I-476J-1435D01*
G01Y97146D01*
G03X325720Y95711I1512J0D01*
G02X326246Y95332I126J-379D01*
G01Y92661D01*
G02X325720Y92282I-400J0D01*
G03X323732Y90847I-476J-1435D01*
G01Y87697D01*
G03X325720Y86262I1512J0D01*
G02X326246Y85883I126J-379D01*
G01Y83212D01*
G02X325720Y82833I-400J0D01*
G03X323732Y81399I-476J-1435D01*
G01Y78248D01*
G03X325720Y76813I1512J0D01*
G02X326246Y76434I126J-379D01*
G01Y73763D01*
G02X325720Y73384I-400J0D01*
G03X323732Y71949I-476J-1435D01*
G01Y68799D01*
G03X325720Y67364I1512J0D01*
G02X326246Y66985I126J-379D01*
G01Y64314D01*
G02X325720Y63935I-400J0D01*
G03X323732Y62501I-476J-1435D01*
G01Y59351D01*
G03X325720Y57916I1512J0D01*
G02X326246Y57537I126J-379D01*
G01Y46004D01*
G02X326181Y45939I-65J0D01*
G01X321062D01*
G03X317190Y42067I1J-3873D01*
G01Y25334D01*
G03X321062Y21462I3873J1D01*
G01X347441D01*
G02X347505Y21398I0J-64D01*
G01Y1968D01*
G02X347441Y1904I-64J0D01*
G01X223819D01*
G37*
%LPD*%
G75*
G36*
G01X289288Y198561D02*
G02X293312I2012J0D01*
G01Y195360D01*
G02X289288Y195361I-2012J1D01*
G01Y198561D01*
G37*
G36*
G01X300388Y137043D02*
G02X305212I2412J0D01*
G01Y132642D01*
G02X300388Y132643I-2412J1D01*
G01Y137043D01*
G37*
G36*
G01X292988Y89899D02*
G02X297012I2012J0D01*
G01Y86698D01*
G02X292988Y86699I-2012J1D01*
G01Y89899D01*
G37*
G36*
G01X277512Y222811D02*
Y218371D01*
G02X272688Y218372I-2412J1D01*
G01Y222812D01*
G02X277512Y222811I2412J-1D01*
G37*
G36*
G01X275512Y211000D02*
Y206560D01*
G02X270688Y206561I-2412J1D01*
G01Y211001D01*
G02X275512Y211000I2412J-1D01*
G37*
G36*
G01Y102339D02*
Y97898D01*
G02X270688Y97899I-2412J1D01*
G01Y102339D01*
G02X275512I2412J0D01*
G37*
G36*
G01X260750Y65189D02*
X259311Y63750D01*
X232689D01*
X231250Y65189D01*
Y306811D01*
X232689Y308250D01*
X242013D01*
X242033Y308254D01*
G02X242967I467J-2254D01*
G01X242987Y308250D01*
X246013D01*
X246033Y308254D01*
G02X246967I467J-2254D01*
G01X246987Y308250D01*
X250013D01*
X250033Y308254D01*
G02X250967I467J-2254D01*
G01X250987Y308250D01*
X259311D01*
X260750Y306811D01*
Y168921D01*
G02Y167079I-2000J-921D01*
G01Y65189D01*
G37*
G54D25*
X265551Y143464D03*
Y252126D03*
G54D24*
Y64724D03*
Y173386D03*
X311614Y31870D03*
G54D26*
Y185414D03*
G54D23*
X275100Y111930D03*
%LPC*%
G75*
G36*
G01X259250Y65811D02*
X258689Y65250D01*
X233311D01*
X232750Y65811D01*
Y306189D01*
X233311Y306750D01*
X258689D01*
X259250Y306189D01*
Y65811D01*
G37*
%LPD*%
G75*
G54D15*
X95000Y277500D03*
X99000D03*
X106500D03*
X92500Y295000D03*
X106137Y286000D03*
X100000Y288500D03*
X92500Y298500D03*
Y309000D03*
X107000Y311500D03*
Y308000D03*
X100250Y313200D03*
X103500Y317000D03*
Y321000D03*
X91500Y312500D03*
X96750Y328500D03*
X100500Y347289D03*
X121500Y276500D03*
X118000D03*
X114500D03*
X110500Y277500D03*
X121456Y289154D03*
X112500Y289000D03*
X108000Y295000D03*
Y298500D03*
X115000Y305000D03*
X119000D03*
X108000Y303100D03*
X120120Y315000D03*
X116500D03*
X109500Y334500D03*
X113000D03*
X117000D03*
X121000D03*
X125000Y277000D03*
X128500Y282500D03*
X126000Y287000D03*
X130000Y298500D03*
X215064Y316100D03*
X236805Y146452D03*
X237000Y156000D03*
Y159780D03*
Y152500D03*
X236500Y168500D03*
X225000Y169500D03*
X237000Y164250D03*
X252000Y151500D03*
Y155000D03*
Y160500D03*
X251500Y164500D03*
X263000Y96500D03*
Y88500D03*
Y81338D03*
Y84838D03*
Y104000D03*
X262819Y100157D03*
X268140Y161221D03*
X258750Y168000D03*
X263000Y190000D03*
Y193500D03*
Y205000D03*
Y197000D03*
Y212500D03*
X262819Y208819D03*
X263000Y240315D03*
X275100Y109710D03*
X273100Y102299D03*
Y97899D03*
X275100Y114110D03*
X279000Y166000D03*
X273100Y210961D03*
Y206561D03*
X275100Y222772D03*
Y218372D03*
X295000Y86699D03*
Y89899D03*
X301000Y125000D03*
X292000Y126000D03*
X302800Y137043D03*
Y132643D03*
X290500Y154250D03*
X296500Y157500D03*
X290500Y150750D03*
X291000Y169500D03*
X291300Y195361D03*
Y198561D03*
X325244Y49902D03*
Y53051D03*
Y62500D03*
Y59351D03*
Y78248D03*
Y68799D03*
Y71949D03*
Y97146D03*
Y87697D03*
Y90847D03*
Y81398D03*
Y106595D03*
Y109744D03*
Y100296D03*
Y156988D03*
Y160138D03*
Y150689D03*
Y147540D03*
Y166437D03*
Y169587D03*
G54D14*
X72000Y286000D03*
Y290000D03*
X58000Y310689D03*
X79000Y344000D03*
Y348000D03*
X138500Y299500D03*
X134500Y307500D03*
X138500Y303500D03*
Y307500D03*
X137500Y324500D03*
X142500Y299500D03*
Y303500D03*
Y307500D03*
X141811Y324500D03*
X145811D03*
X153811D03*
X149811D03*
X162311Y293000D03*
X160811Y310000D03*
X169811Y309500D03*
X172311Y305500D03*
X157811Y324500D03*
X161811D03*
X169811D03*
X165811D03*
X169811Y313500D03*
X176311Y294000D03*
X181061Y297750D03*
X176168Y305500D03*
X195811Y296000D03*
X200811Y308000D03*
Y311000D03*
Y317000D03*
Y314000D03*
X218000Y292000D03*
X215811Y300000D03*
X222311Y325000D03*
X218311D03*
X230000Y96500D03*
X225000Y205000D03*
X222911Y287089D03*
X249000Y260000D03*
X262920Y131653D03*
X273000Y92283D03*
X299500Y46000D03*
X303500D03*
X296500Y61000D03*
X300500D03*
X301500Y49000D03*
X297500D03*
X295500Y52000D03*
X299500D03*
X295500Y110000D03*
X295311Y127600D03*
X304500Y123820D03*
X301711Y245000D03*
G54D17*
X265551Y143464D03*
Y252126D03*
G54D16*
Y64724D03*
Y173386D03*
X311614Y31870D03*
G54D20*
Y185414D03*
G54D18*
X302000Y290500D03*
Y300500D03*
G54D12*
X10000Y330000D03*
Y345000D03*
Y360000D03*
X40000Y270000D03*
Y285000D03*
Y300000D03*
Y330000D03*
Y345000D03*
X25000Y360000D03*
X40000D03*
X55000Y270000D03*
Y285000D03*
Y360000D03*
X70000Y270000D03*
Y360000D03*
X85000Y270000D03*
Y360000D03*
X100000Y270000D03*
X103000Y277500D03*
X96750Y313250D03*
X103750Y313200D03*
X100500Y335689D03*
X100000Y360000D03*
X122100Y280750D03*
X122000Y301000D03*
X115000Y360000D03*
X124000Y315000D03*
X138000Y341500D03*
X130000Y360000D03*
X138000Y345500D03*
X140500Y281000D03*
X146500Y303500D03*
X150500D03*
X146500Y307500D03*
X150500D03*
X155000Y301350D03*
X149811Y341500D03*
X141811D03*
X145811D03*
X153811D03*
X145000Y360000D03*
X149811Y345500D03*
X141811D03*
X145811D03*
X153811D03*
X164811Y304000D03*
X165811Y341500D03*
X157811D03*
X161811D03*
X169811D03*
X160000Y360000D03*
X165811Y345500D03*
X169811D03*
X157811D03*
X161811D03*
X185811Y304200D03*
Y310500D03*
X181811D03*
Y318500D03*
X185811Y314500D03*
Y326500D03*
Y322500D03*
Y318500D03*
X181811Y326500D03*
Y322500D03*
Y314500D03*
X184500Y334000D03*
Y338000D03*
X175000Y360000D03*
X189811Y310500D03*
Y318500D03*
Y322500D03*
Y326500D03*
Y314500D03*
X190000Y360000D03*
X205000D03*
X220000D03*
X225000Y35000D03*
Y50000D03*
Y80000D03*
Y65000D03*
X230000Y75000D03*
Y67000D03*
Y71000D03*
X225000Y95000D03*
Y110000D03*
X230000Y126000D03*
Y130000D03*
Y122000D03*
Y138500D03*
Y142500D03*
Y134500D03*
X225000Y160250D03*
Y149250D03*
Y164250D03*
X230000Y175500D03*
Y179500D03*
Y183500D03*
Y243000D03*
Y234500D03*
Y238500D03*
Y230500D03*
Y247000D03*
Y251000D03*
X237500Y340000D03*
Y344000D03*
Y336000D03*
X235000Y360000D03*
X255000Y5000D03*
Y35000D03*
X247000Y68838D03*
Y72838D03*
X251000Y68838D03*
Y72838D03*
Y88500D03*
X247000Y123838D03*
X251000D03*
X247000Y127838D03*
X251000D03*
X247000Y136338D03*
Y140838D03*
X251000D03*
Y136338D03*
Y177500D03*
X247000D03*
X251000Y181500D03*
X247000D03*
X251000Y197000D03*
Y245000D03*
X247000D03*
X251000Y236500D03*
X247000D03*
X251000Y232500D03*
X247000D03*
X251000Y249500D03*
X247000D03*
X242500Y294000D03*
X246500D03*
X250500D03*
X242500Y306000D03*
Y302000D03*
Y298000D03*
X246500Y306000D03*
Y302000D03*
Y298000D03*
X250500D03*
Y302000D03*
Y306000D03*
X241500Y336000D03*
Y344000D03*
Y340000D03*
X250000Y360000D03*
X270000Y5000D03*
Y35000D03*
X269650Y97899D03*
X271650Y109710D03*
X269650Y102299D03*
X271650Y114110D03*
X271250Y138750D03*
X267700Y153250D03*
X269650Y210961D03*
Y206561D03*
X271650Y222772D03*
Y218372D03*
X265000Y270000D03*
Y285000D03*
X271500Y294000D03*
X267500D03*
X271500Y306000D03*
Y302000D03*
Y298000D03*
X267500D03*
Y302000D03*
Y306000D03*
X260500Y340000D03*
Y344000D03*
Y336000D03*
X256500D03*
Y344000D03*
Y340000D03*
X265000Y360000D03*
X282500Y5000D03*
X272500Y20000D03*
X285000Y32500D03*
X275500Y63346D03*
X280000Y71614D03*
Y67677D03*
X280169Y126732D03*
Y120826D03*
X275768Y144842D03*
X280169Y138543D03*
Y132637D03*
X278860Y162250D03*
X280000Y176339D03*
X275500Y172008D03*
X280000Y180276D03*
X273500Y194055D03*
Y199961D03*
X273600Y240250D03*
X280169Y247205D03*
X275768Y253504D03*
X280000Y270000D03*
X275500Y294000D03*
X280000Y285000D03*
X275500Y298000D03*
Y302000D03*
Y306000D03*
X280000Y300000D03*
Y315000D03*
X295000Y5000D03*
X300000Y20000D03*
Y35000D03*
X304565Y61142D03*
Y96142D03*
X304500Y92000D03*
X291500Y97204D03*
X291550Y91299D03*
X291500Y85393D03*
X295500Y100000D03*
X291500Y109960D03*
Y101960D03*
Y114921D03*
X300500Y129100D03*
X299300Y137043D03*
X304565Y141142D03*
X299300Y132643D03*
X302000Y157500D03*
X292000Y181500D03*
X294750Y195261D03*
X295500Y208461D03*
X294750Y198661D03*
X291500Y210961D03*
Y205866D03*
Y218461D03*
Y223583D03*
Y241299D03*
Y229488D03*
Y235394D03*
X295000Y270000D03*
Y285000D03*
Y300000D03*
Y315000D03*
X315000Y5000D03*
Y20000D03*
Y40000D03*
X313000Y179500D03*
X310000Y225000D03*
Y240000D03*
Y255000D03*
Y270000D03*
Y285000D03*
Y300000D03*
Y315000D03*
Y330000D03*
Y360000D03*
Y345000D03*
X325244Y56201D03*
Y75099D03*
Y65650D03*
Y93996D03*
Y84548D03*
Y112894D03*
Y103445D03*
Y128642D03*
Y119193D03*
Y144390D03*
Y138091D03*
Y153839D03*
Y163288D03*
X324302Y203977D03*
X325000Y225000D03*
Y240000D03*
Y255000D03*
Y270000D03*
Y285000D03*
Y300000D03*
Y315000D03*
Y330000D03*
Y360000D03*
Y345000D03*
X345000Y5000D03*
Y20000D03*
X340000Y285000D03*
Y300000D03*
Y315000D03*
Y330000D03*
Y360000D03*
Y345000D03*
G54D19*
X302000Y310500D03*
G54D10*
X26087Y-114844D03*
X26435Y373984D03*
X175335Y62719D03*
Y189062D03*
X547104Y69007D03*
Y195351D03*
X696192Y373984D03*
G54D13*
X52500Y325189D03*
Y331189D03*
X59500Y294189D03*
X64500Y309589D03*
X59500Y299939D03*
X71500Y315689D03*
X67900D03*
X72000Y336689D03*
X89000Y295189D03*
Y291189D03*
Y287189D03*
Y283189D03*
Y303689D03*
Y299689D03*
X75100Y315689D03*
X89000Y329189D03*
Y333189D03*
G54D11*
X25596Y316176D03*
X237013Y17712D03*
X287407Y345704D03*
%LPC*%
G75*
G54D21*
G01X-176139Y-183003D02*
G02I-12000J0D01*
G01X-181289D02*
G02I-6850J0D01*
G01X-172139D02*
X-204139D01*
G01X-188139Y-199003D02*
Y-167003D01*
G01X-172139Y-199003D02*
Y-279003D01*
G01D02*
X1178561D01*
G01X-172139Y-234503D02*
X1178561D01*
G01X-172139Y-199003D02*
X1178561D01*
G01X391061D02*
Y-279003D01*
G01X528561Y-199003D02*
Y-279003D01*
G01X643561Y-199003D02*
Y-279003D01*
G01X811061Y-199003D02*
Y-279003D01*
G01X981061Y-199003D02*
Y-279003D01*
G01X1178561Y-199003D02*
Y-279003D01*
G01X1210561Y-183003D02*
X1178561D01*
G01X1206561D02*
G02I-12000J0D01*
G01X1201411D02*
G02I-6850J0D01*
G01X1194561Y-199003D02*
Y-167003D01*
G54D22*
G01X-148956Y-251503D02*
Y-269003D01*
X-140222D01*
G01X-127089Y-257337D02*
Y-269003D01*
G01Y-252670D02*
X-127526Y-252378D01*
Y-251795D01*
X-127089Y-251503D01*
X-126652Y-251795D01*
Y-252378D01*
X-127089Y-252670D01*
G01X-112646Y-273378D02*
X-111117Y-274545D01*
X-109371Y-274836D01*
X-107843Y-274545D01*
X-106532Y-273087D01*
X-105659Y-271045D01*
Y-257337D01*
G01Y-259670D02*
X-106532Y-258503D01*
X-107843Y-257628D01*
X-109371Y-257337D01*
X-111117Y-257920D01*
X-112209Y-259086D01*
X-113083Y-261128D01*
X-113519Y-263170D01*
X-113301Y-264920D01*
X-112427Y-266962D01*
X-111117Y-268420D01*
X-109371Y-269003D01*
X-108061Y-268711D01*
X-106532Y-267545D01*
X-105659Y-266379D01*
G01X-95801Y-269003D02*
Y-251503D01*
G01Y-259961D02*
X-94709Y-258503D01*
X-93617Y-257628D01*
X-91871Y-257337D01*
X-90561Y-257628D01*
X-89032Y-258795D01*
X-88377Y-260545D01*
Y-269003D01*
G01X-74589Y-251503D02*
Y-269003D01*
G01X-77646Y-257337D02*
X-71532D01*
G01X-60801Y-269003D02*
Y-257337D01*
G01Y-260253D02*
X-59927Y-258795D01*
X-58617Y-257628D01*
X-56871Y-257337D01*
X-55343Y-257628D01*
X-54032Y-258795D01*
X-53377Y-260836D01*
Y-269003D01*
G01X-39589Y-257337D02*
Y-269003D01*
G01Y-252670D02*
X-40026Y-252378D01*
Y-251795D01*
X-39589Y-251503D01*
X-39152Y-251795D01*
Y-252378D01*
X-39589Y-252670D01*
G01X-25801Y-269003D02*
Y-257337D01*
G01Y-260253D02*
X-24927Y-258795D01*
X-23617Y-257628D01*
X-21871Y-257337D01*
X-20343Y-257628D01*
X-19032Y-258795D01*
X-18377Y-260836D01*
Y-269003D01*
G01X-7646Y-273378D02*
X-6117Y-274545D01*
X-4371Y-274836D01*
X-2843Y-274545D01*
X-1532Y-273087D01*
X-659Y-271045D01*
Y-257337D01*
G01Y-259670D02*
X-1532Y-258503D01*
X-2843Y-257628D01*
X-4371Y-257337D01*
X-6117Y-257920D01*
X-7209Y-259086D01*
X-8083Y-261128D01*
X-8519Y-263170D01*
X-8301Y-264920D01*
X-7427Y-266962D01*
X-6117Y-268420D01*
X-4371Y-269003D01*
X-3061Y-268711D01*
X-1532Y-267545D01*
X-659Y-266379D01*
G01X26044Y-269003D02*
Y-251503D01*
X31284D01*
X33031Y-252378D01*
X34341Y-254420D01*
X34778Y-256753D01*
X34341Y-259086D01*
X33249Y-260836D01*
X31284Y-261712D01*
X26044D01*
G01X42452Y-251503D02*
X47911Y-269003D01*
X53370Y-251503D01*
G01X65411D02*
Y-269003D01*
G01X60389Y-251503D02*
X70433D01*
G01X94734Y-269003D02*
Y-251503D01*
X100411Y-266086D01*
X106088Y-251503D01*
Y-269003D01*
G01X117911Y-269586D02*
X117474Y-269295D01*
Y-268711D01*
X117911Y-268420D01*
X118348Y-268711D01*
Y-269295D01*
X117911Y-269586D01*
G01X131263Y-254420D02*
X132573Y-252670D01*
X134101Y-251795D01*
X135848Y-251503D01*
X138031Y-252086D01*
X139559Y-253545D01*
X139996Y-255294D01*
X139778Y-257045D01*
X138904Y-258503D01*
X134538Y-261420D01*
X132573Y-263461D01*
X131263Y-266379D01*
X130826Y-269003D01*
X139996D01*
G01X164952D02*
X170411Y-251503D01*
X175870Y-269003D01*
G01X173904Y-262878D02*
X166917D01*
G01X191841Y-251503D02*
Y-269003D01*
G01Y-266379D02*
X190968Y-267837D01*
X189657Y-268711D01*
X188129Y-269003D01*
X186383Y-268420D01*
X185073Y-266962D01*
X184199Y-265212D01*
X183981Y-263170D01*
X184199Y-261128D01*
X185073Y-259378D01*
X186383Y-257920D01*
X188129Y-257337D01*
X189657Y-257628D01*
X190749Y-258212D01*
X191841Y-259378D01*
G01X209341Y-269003D02*
Y-257337D01*
G01Y-259378D02*
X208468Y-258212D01*
X207157Y-257628D01*
X205629Y-257337D01*
X204101Y-257920D01*
X202791Y-259086D01*
X201917Y-260836D01*
X201481Y-263170D01*
X201917Y-265503D01*
X202791Y-267253D01*
X204101Y-268420D01*
X205629Y-269003D01*
X207157Y-268711D01*
X208468Y-267837D01*
X209341Y-266670D01*
G01X218981Y-274836D02*
Y-257337D01*
G01Y-259961D02*
X220073Y-258503D01*
X221164Y-257628D01*
X222911Y-257337D01*
X224439Y-257628D01*
X225968Y-259086D01*
X226623Y-261128D01*
X226841Y-263170D01*
X226623Y-265212D01*
X225968Y-267253D01*
X224657Y-268420D01*
X222911Y-269003D01*
X221383Y-268711D01*
X219854Y-267837D01*
X218981Y-266670D01*
G01X240411Y-251503D02*
Y-269003D01*
G01X237354Y-257337D02*
X243468D01*
G01X257911Y-269003D02*
X256601Y-268711D01*
X255291Y-267545D01*
X254417Y-265503D01*
X253981Y-263170D01*
X254417Y-260836D01*
X255291Y-258795D01*
X256601Y-257628D01*
X257911Y-257337D01*
X259221Y-257628D01*
X260531Y-258795D01*
X261404Y-260836D01*
X261623Y-263170D01*
X261404Y-265503D01*
X260531Y-267545D01*
X259221Y-268711D01*
X257911Y-269003D01*
G01X272354D02*
Y-257337D01*
G01Y-259670D02*
X273446Y-258503D01*
X274538Y-257628D01*
X276066Y-257337D01*
X277157Y-257628D01*
X278468Y-258503D01*
G01X315214Y-252962D02*
X313904Y-252086D01*
X312376Y-251503D01*
X310629D01*
X308664Y-252378D01*
X307136Y-253836D01*
X306044Y-255587D01*
X305171Y-258503D01*
X304952Y-261128D01*
X305389Y-263753D01*
X306044Y-265503D01*
X307354Y-267253D01*
X308883Y-268420D01*
X310411Y-269003D01*
X311939D01*
X313468Y-268420D01*
X314778Y-267545D01*
X315870Y-266379D01*
G01X331841Y-269003D02*
Y-257337D01*
G01Y-259378D02*
X330968Y-258212D01*
X329657Y-257628D01*
X328129Y-257337D01*
X326601Y-257920D01*
X325291Y-259086D01*
X324417Y-260836D01*
X323981Y-263170D01*
X324417Y-265503D01*
X325291Y-267253D01*
X326601Y-268420D01*
X328129Y-269003D01*
X329657Y-268711D01*
X330968Y-267837D01*
X331841Y-266670D01*
G01X342354Y-269003D02*
Y-257337D01*
G01Y-259670D02*
X343446Y-258503D01*
X344538Y-257628D01*
X346066Y-257337D01*
X347157Y-257628D01*
X348468Y-258503D01*
G01X366841Y-251503D02*
Y-269003D01*
G01Y-266379D02*
X365968Y-267837D01*
X364657Y-268711D01*
X363129Y-269003D01*
X361383Y-268420D01*
X360073Y-266962D01*
X359199Y-265212D01*
X358981Y-263170D01*
X359199Y-261128D01*
X360073Y-259378D01*
X361383Y-257920D01*
X363129Y-257337D01*
X364657Y-257628D01*
X365749Y-258212D01*
X366841Y-259378D01*
G01X68484Y-224003D02*
Y-206503D01*
X74161Y-221086D01*
X79838Y-206503D01*
Y-224003D01*
G01X91661D02*
X90351Y-223711D01*
X89041Y-222545D01*
X88167Y-220503D01*
X87731Y-218170D01*
X88167Y-215836D01*
X89041Y-213795D01*
X90351Y-212628D01*
X91661Y-212337D01*
X92971Y-212628D01*
X94281Y-213795D01*
X95154Y-215836D01*
X95373Y-218170D01*
X95154Y-220503D01*
X94281Y-222545D01*
X92971Y-223711D01*
X91661Y-224003D01*
G01X113091Y-206503D02*
Y-224003D01*
G01Y-221379D02*
X112218Y-222837D01*
X110907Y-223711D01*
X109379Y-224003D01*
X107633Y-223420D01*
X106323Y-221962D01*
X105449Y-220212D01*
X105231Y-218170D01*
X105449Y-216128D01*
X106323Y-214378D01*
X107633Y-212920D01*
X109379Y-212337D01*
X110907Y-212628D01*
X111999Y-213212D01*
X113091Y-214378D01*
G01X123386Y-216128D02*
X130373D01*
X129718Y-214086D01*
X128626Y-212920D01*
X127098Y-212337D01*
X125569Y-212628D01*
X124259Y-213503D01*
X123386Y-215545D01*
X122949Y-217295D01*
Y-219045D01*
X123386Y-220795D01*
X124478Y-222545D01*
X125788Y-223711D01*
X127316Y-224003D01*
X128844Y-223420D01*
X130373Y-221670D01*
G01X144161Y-224003D02*
Y-206503D01*
G01X424761Y-269003D02*
Y-251503D01*
X422141Y-255003D01*
G01Y-269003D02*
X427381D01*
G01X437458Y-266379D02*
X438767Y-267837D01*
X440296Y-268711D01*
X442261Y-269003D01*
X444226Y-268420D01*
X445754Y-267253D01*
X446846Y-265212D01*
X447064Y-262878D01*
X446628Y-260545D01*
X445536Y-259086D01*
X444007Y-257920D01*
X442479Y-257628D01*
X440951Y-257920D01*
X438986Y-259086D01*
X439641Y-251503D01*
X445536D01*
G01X459324Y-269003D02*
X459761Y-265212D01*
X460416Y-262003D01*
X461289Y-259086D01*
X462381Y-255878D01*
X464128Y-251503D01*
X455394D01*
G01X472458Y-266379D02*
X473767Y-267837D01*
X475296Y-268711D01*
X477261Y-269003D01*
X479226Y-268420D01*
X480754Y-267253D01*
X481846Y-265212D01*
X482064Y-262878D01*
X481628Y-260545D01*
X480536Y-259086D01*
X479007Y-257920D01*
X477479Y-257628D01*
X475951Y-257920D01*
X473986Y-259086D01*
X474641Y-251503D01*
X480536D01*
G01X494761D02*
X493014Y-252086D01*
X491704Y-253545D01*
X490831Y-255294D01*
X490176Y-257628D01*
X489958Y-260253D01*
X490176Y-262878D01*
X490831Y-265212D01*
X491704Y-266962D01*
X493014Y-268420D01*
X494761Y-269003D01*
X496507Y-268420D01*
X497818Y-266962D01*
X498691Y-265212D01*
X499346Y-262878D01*
X499564Y-260253D01*
X499346Y-257628D01*
X498691Y-255294D01*
X497818Y-253545D01*
X496507Y-252086D01*
X494761Y-251503D01*
G01X411644Y-224003D02*
Y-206503D01*
X416884D01*
X418631Y-207378D01*
X419941Y-209420D01*
X420378Y-211753D01*
X419941Y-214086D01*
X418849Y-215836D01*
X416884Y-216712D01*
X411644D01*
G01X438314Y-207962D02*
X437004Y-207086D01*
X435476Y-206503D01*
X433729D01*
X431764Y-207378D01*
X430236Y-208836D01*
X429144Y-210587D01*
X428271Y-213503D01*
X428052Y-216128D01*
X428489Y-218753D01*
X429144Y-220503D01*
X430454Y-222253D01*
X431983Y-223420D01*
X433511Y-224003D01*
X435039D01*
X436568Y-223420D01*
X437878Y-222545D01*
X438970Y-221379D01*
G01X452757Y-214670D02*
X453631Y-213795D01*
X454286Y-212337D01*
X454723Y-210294D01*
X454286Y-208545D01*
X453413Y-207378D01*
X451884Y-206503D01*
X445989D01*
Y-224003D01*
X453194D01*
X454723Y-222837D01*
X455596Y-221086D01*
X456033Y-219045D01*
X455596Y-217003D01*
X454286Y-215253D01*
X452757Y-214670D01*
X445989D01*
G01X461961Y-229836D02*
X475061D01*
G01X480989Y-224003D02*
Y-206503D01*
X491033Y-224003D01*
Y-206503D01*
G01X503511Y-224003D02*
X501764Y-223711D01*
X500236Y-222545D01*
X498926Y-220795D01*
X498052Y-218753D01*
X497616Y-216420D01*
Y-214086D01*
X498052Y-211753D01*
X498926Y-209711D01*
X500236Y-207962D01*
X501764Y-206795D01*
X503511Y-206503D01*
X505257Y-206795D01*
X506786Y-207962D01*
X508096Y-209711D01*
X508970Y-211753D01*
X509406Y-214086D01*
Y-216420D01*
X508970Y-218753D01*
X508096Y-220795D01*
X506786Y-222545D01*
X505257Y-223711D01*
X503511Y-224003D01*
G01X554352Y-206503D02*
X559811Y-224003D01*
X565270Y-206503D01*
G01X581678Y-224003D02*
X572944D01*
Y-206503D01*
X581678D01*
G01X578184Y-214961D02*
X572944D01*
G01X590444Y-224003D02*
Y-206503D01*
X595903D01*
X597649Y-207378D01*
X598741Y-208545D01*
X599178Y-210878D01*
X598741Y-213212D01*
X597431Y-214670D01*
X595903Y-215545D01*
X590444D01*
G01X595903D02*
X599178Y-224003D01*
G01X612311Y-224586D02*
X611874Y-224295D01*
Y-223711D01*
X612311Y-223420D01*
X612748Y-223711D01*
Y-224295D01*
X612311Y-224586D01*
G01X586061Y-269003D02*
Y-251503D01*
X583441Y-255003D01*
G01Y-269003D02*
X588681D01*
G01X766628Y-251503D02*
Y-269003D01*
X757894D01*
G01X749564Y-266379D02*
X748255Y-267837D01*
X746726Y-268711D01*
X744761Y-269003D01*
X742796Y-268420D01*
X741268Y-267253D01*
X740176Y-265212D01*
X739958Y-262878D01*
X740394Y-260545D01*
X741486Y-259086D01*
X743015Y-257920D01*
X744543Y-257628D01*
X746071Y-257920D01*
X748036Y-259086D01*
X747381Y-251503D01*
X741486D01*
G01X725951Y-260253D02*
X721584D01*
Y-265503D01*
X722894Y-267253D01*
X724423Y-268420D01*
X726606Y-269003D01*
X728789Y-268420D01*
X730318Y-267253D01*
X731628Y-265503D01*
X732501Y-263461D01*
X732938Y-261128D01*
Y-259086D01*
X732501Y-257337D01*
X731628Y-255294D01*
X730318Y-253545D01*
X729008Y-252378D01*
X727261Y-251503D01*
X725733D01*
X723986Y-252086D01*
X722676Y-253253D01*
G01X714783Y-269003D02*
Y-251503D01*
X704739Y-269003D01*
Y-251503D01*
G01X697064Y-269003D02*
Y-251503D01*
X692698D01*
X690951Y-252378D01*
X689641Y-253545D01*
X688549Y-255294D01*
X687676Y-257337D01*
X687458Y-260253D01*
X687676Y-263170D01*
X688549Y-265212D01*
X689641Y-266962D01*
X690951Y-268128D01*
X692698Y-269003D01*
X697064D01*
G01X687894Y-206503D02*
Y-224003D01*
X696628D01*
G01X713691D02*
Y-212337D01*
G01Y-214378D02*
X712818Y-213212D01*
X711507Y-212628D01*
X709979Y-212337D01*
X708451Y-212920D01*
X707141Y-214086D01*
X706267Y-215836D01*
X705831Y-218170D01*
X706267Y-220503D01*
X707141Y-222253D01*
X708451Y-223420D01*
X709979Y-224003D01*
X711507Y-223711D01*
X712818Y-222837D01*
X713691Y-221670D01*
G01X722676Y-229253D02*
X723986Y-229836D01*
X725733Y-229253D01*
X726824Y-228087D01*
X727698Y-226628D01*
X729007Y-221962D01*
X731846Y-212337D01*
G01X724859D02*
X729007Y-221962D01*
G01X741486Y-216128D02*
X748473D01*
X747818Y-214086D01*
X746726Y-212920D01*
X745198Y-212337D01*
X743669Y-212628D01*
X742359Y-213503D01*
X741486Y-215545D01*
X741049Y-217295D01*
Y-219045D01*
X741486Y-220795D01*
X742578Y-222545D01*
X743888Y-223711D01*
X745416Y-224003D01*
X746944Y-223420D01*
X748473Y-221670D01*
G01X759204Y-224003D02*
Y-212337D01*
G01Y-214670D02*
X760296Y-213503D01*
X761388Y-212628D01*
X762916Y-212337D01*
X764007Y-212628D01*
X765318Y-213503D01*
G01X830008Y-224003D02*
Y-206503D01*
X834374D01*
X836121Y-207378D01*
X837431Y-208545D01*
X838523Y-210294D01*
X839396Y-212337D01*
X839614Y-215253D01*
X839396Y-218170D01*
X838523Y-220212D01*
X837431Y-221962D01*
X836121Y-223128D01*
X834374Y-224003D01*
X830008D01*
G01X849036Y-216128D02*
X856023D01*
X855368Y-214086D01*
X854276Y-212920D01*
X852748Y-212337D01*
X851219Y-212628D01*
X849909Y-213503D01*
X849036Y-215545D01*
X848599Y-217295D01*
Y-219045D01*
X849036Y-220795D01*
X850128Y-222545D01*
X851438Y-223711D01*
X852966Y-224003D01*
X854494Y-223420D01*
X856023Y-221670D01*
G01X866536Y-221962D02*
X867628Y-223128D01*
X869156Y-224003D01*
X870466D01*
X871776Y-223420D01*
X872649Y-222545D01*
X873086Y-221379D01*
X872868Y-219628D01*
X871994Y-218753D01*
X868064Y-217003D01*
X867191Y-214961D01*
X867628Y-213503D01*
X868501Y-212628D01*
X869811Y-212337D01*
X871121Y-212628D01*
X872431Y-213503D01*
G01X887311Y-212337D02*
Y-224003D01*
G01Y-207670D02*
X886874Y-207378D01*
Y-206795D01*
X887311Y-206503D01*
X887748Y-206795D01*
Y-207378D01*
X887311Y-207670D01*
G01X901754Y-228378D02*
X903283Y-229545D01*
X905029Y-229836D01*
X906557Y-229545D01*
X907868Y-228087D01*
X908741Y-226045D01*
Y-212337D01*
G01Y-214670D02*
X907868Y-213503D01*
X906557Y-212628D01*
X905029Y-212337D01*
X903283Y-212920D01*
X902191Y-214086D01*
X901317Y-216128D01*
X900881Y-218170D01*
X901099Y-219920D01*
X901973Y-221962D01*
X903283Y-223420D01*
X905029Y-224003D01*
X906339Y-223711D01*
X907868Y-222545D01*
X908741Y-221379D01*
G01X918599Y-224003D02*
Y-212337D01*
G01Y-215253D02*
X919473Y-213795D01*
X920783Y-212628D01*
X922529Y-212337D01*
X924057Y-212628D01*
X925368Y-213795D01*
X926023Y-215836D01*
Y-224003D01*
G01X936536Y-216128D02*
X943523D01*
X942868Y-214086D01*
X941776Y-212920D01*
X940248Y-212337D01*
X938719Y-212628D01*
X937409Y-213503D01*
X936536Y-215545D01*
X936099Y-217295D01*
Y-219045D01*
X936536Y-220795D01*
X937628Y-222545D01*
X938938Y-223711D01*
X940466Y-224003D01*
X941994Y-223420D01*
X943523Y-221670D01*
G01X954254Y-224003D02*
Y-212337D01*
G01Y-214670D02*
X955346Y-213503D01*
X956438Y-212628D01*
X957966Y-212337D01*
X959057Y-212628D01*
X960368Y-213503D01*
G01X874194Y-265503D02*
X875286Y-267253D01*
X876596Y-268420D01*
X878124Y-269003D01*
X879871Y-268420D01*
X881181Y-267253D01*
X882491Y-265503D01*
X882928Y-263170D01*
Y-251503D01*
G01X896061Y-269003D02*
X894314Y-268711D01*
X892786Y-267545D01*
X891476Y-265795D01*
X890602Y-263753D01*
X890166Y-261420D01*
Y-259086D01*
X890602Y-256753D01*
X891476Y-254711D01*
X892786Y-252962D01*
X894314Y-251795D01*
X896061Y-251503D01*
X897807Y-251795D01*
X899336Y-252962D01*
X900646Y-254711D01*
X901520Y-256753D01*
X901956Y-259086D01*
Y-261420D01*
X901520Y-263753D01*
X900646Y-265795D01*
X899336Y-267545D01*
X897807Y-268711D01*
X896061Y-269003D01*
G01X913561D02*
Y-261128D01*
X909194Y-251503D01*
G01X917928D02*
X913561Y-261128D01*
G01X1001011Y-269003D02*
Y-251503D01*
X998391Y-255003D01*
G01Y-269003D02*
X1003631D01*
G01X1014363Y-254420D02*
X1015673Y-252670D01*
X1017201Y-251795D01*
X1018948Y-251503D01*
X1021131Y-252086D01*
X1022659Y-253545D01*
X1023096Y-255294D01*
X1022878Y-257045D01*
X1022004Y-258503D01*
X1017638Y-261420D01*
X1015673Y-263461D01*
X1014363Y-266379D01*
X1013926Y-269003D01*
X1023096D01*
G01X1032081Y-269586D02*
X1039941Y-251503D01*
G01X1048708Y-265503D02*
X1050017Y-267545D01*
X1051764Y-268711D01*
X1053729Y-269003D01*
X1055476Y-268711D01*
X1057223Y-267253D01*
X1058314Y-265503D01*
X1058533Y-263753D01*
X1058096Y-261712D01*
X1056568Y-260253D01*
X1055039Y-259670D01*
X1053074D01*
G01X1055039D02*
X1056349Y-258795D01*
X1057441Y-257337D01*
X1057878Y-255587D01*
X1057441Y-253836D01*
X1056349Y-252378D01*
X1054384Y-251503D01*
X1052419Y-251795D01*
X1050454Y-252962D01*
G01X1071011Y-251503D02*
X1069264Y-252086D01*
X1067954Y-253545D01*
X1067081Y-255294D01*
X1066426Y-257628D01*
X1066208Y-260253D01*
X1066426Y-262878D01*
X1067081Y-265212D01*
X1067954Y-266962D01*
X1069264Y-268420D01*
X1071011Y-269003D01*
X1072757Y-268420D01*
X1074068Y-266962D01*
X1074941Y-265212D01*
X1075596Y-262878D01*
X1075814Y-260253D01*
X1075596Y-257628D01*
X1074941Y-255294D01*
X1074068Y-253545D01*
X1072757Y-252086D01*
X1071011Y-251503D01*
G01X1084581Y-269586D02*
X1092441Y-251503D01*
G01X1101863Y-254420D02*
X1103173Y-252670D01*
X1104701Y-251795D01*
X1106448Y-251503D01*
X1108631Y-252086D01*
X1110159Y-253545D01*
X1110596Y-255294D01*
X1110378Y-257045D01*
X1109504Y-258503D01*
X1105138Y-261420D01*
X1103173Y-263461D01*
X1101863Y-266379D01*
X1101426Y-269003D01*
X1110596D01*
G01X1123511Y-251503D02*
X1121764Y-252086D01*
X1120454Y-253545D01*
X1119581Y-255294D01*
X1118926Y-257628D01*
X1118708Y-260253D01*
X1118926Y-262878D01*
X1119581Y-265212D01*
X1120454Y-266962D01*
X1121764Y-268420D01*
X1123511Y-269003D01*
X1125257Y-268420D01*
X1126568Y-266962D01*
X1127441Y-265212D01*
X1128096Y-262878D01*
X1128314Y-260253D01*
X1128096Y-257628D01*
X1127441Y-255294D01*
X1126568Y-253545D01*
X1125257Y-252086D01*
X1123511Y-251503D01*
G01X1141011Y-269003D02*
Y-251503D01*
X1138391Y-255003D01*
G01Y-269003D02*
X1143631D01*
G01X1154363Y-261712D02*
X1155891Y-259670D01*
X1157201Y-258503D01*
X1158948Y-257920D01*
X1160476Y-258503D01*
X1161568Y-259670D01*
X1162441Y-261420D01*
X1162659Y-263461D01*
X1162441Y-265212D01*
X1161568Y-266962D01*
X1160257Y-268420D01*
X1158729Y-269003D01*
X1156983Y-268420D01*
X1155454Y-266670D01*
X1154581Y-264045D01*
X1154363Y-261128D01*
X1154799Y-257337D01*
X1155454Y-255294D01*
X1156546Y-253253D01*
X1158074Y-251795D01*
X1159603Y-251503D01*
X1161131Y-252086D01*
X1162223Y-253545D01*
G01X1048708Y-224003D02*
Y-206503D01*
X1053074D01*
X1054821Y-207378D01*
X1056131Y-208545D01*
X1057223Y-210294D01*
X1058096Y-212337D01*
X1058314Y-215253D01*
X1058096Y-218170D01*
X1057223Y-220212D01*
X1056131Y-221962D01*
X1054821Y-223128D01*
X1053074Y-224003D01*
X1048708D01*
G01X1074941D02*
Y-212337D01*
G01Y-214378D02*
X1074068Y-213212D01*
X1072757Y-212628D01*
X1071229Y-212337D01*
X1069701Y-212920D01*
X1068391Y-214086D01*
X1067517Y-215836D01*
X1067081Y-218170D01*
X1067517Y-220503D01*
X1068391Y-222253D01*
X1069701Y-223420D01*
X1071229Y-224003D01*
X1072757Y-223711D01*
X1074068Y-222837D01*
X1074941Y-221670D01*
G01X1088511Y-206503D02*
Y-224003D01*
G01X1085454Y-212337D02*
X1091568D01*
G01X1102736Y-216128D02*
X1109723D01*
X1109068Y-214086D01*
X1107976Y-212920D01*
X1106448Y-212337D01*
X1104919Y-212628D01*
X1103609Y-213503D01*
X1102736Y-215545D01*
X1102299Y-217295D01*
Y-219045D01*
X1102736Y-220795D01*
X1103828Y-222545D01*
X1105138Y-223711D01*
X1106666Y-224003D01*
X1108194Y-223420D01*
X1109723Y-221670D01*
M02*
